(kicad_pcb
	(version 20260206)
	(generator "pcbnew")
	(generator_version "10.0")
	(general
		(thickness 1.21888)
		(legacy_teardrops no)
	)
	(paper "A4")
	(title_block
		(title "timecard-v9 — TimeCard-DC-V9_EXP.PcbDoc")
		(comment 1 "Time Appliance Project (Time Card) / footprints 249-257 of 402")
	)
	(layers
		(0 "F.Cu" signal "TOP")
		(4 "In1.Cu" signal "SGND")
		(6 "In2.Cu" signal "IN1")
		(8 "In3.Cu" signal "IN2")
		(10 "In4.Cu" signal "SGND1")
		(2 "B.Cu" signal "BOTTOM")
		(9 "F.Adhes" user "F.Adhesive")
		(11 "B.Adhes" user "B.Adhesive")
		(13 "F.Paste" user "Top Paste")
		(15 "B.Paste" user "Bottom Paste")
		(5 "F.SilkS" user "Top Overlay")
		(7 "B.SilkS" user "Bottom Overlay")
		(1 "F.Mask" user "Top Solder")
		(3 "B.Mask" user "Bottom Solder")
		(17 "Dwgs.User" user "User.Drawings")
		(19 "Cmts.User" user "User.Comments")
		(21 "Eco1.User" user "User.Eco1")
		(23 "Eco2.User" user "User.Eco2")
		(25 "Edge.Cuts" user)
		(27 "Margin" user)
		(31 "F.CrtYd" user "Top Courtyard")
		(29 "B.CrtYd" user "Bottom Courtyard")
		(35 "F.Fab" user "Top Component Center")
		(33 "B.Fab" user "Bottom Component Center")
	)
	(footprint "GNSS:GNSS Header 16-pin"
		(locked yes)
		(layer "F.Cu")
		(at 103.2491 74.2286)
		(property "Reference" "J6"
			(at 3.943895 1.260669 180)
			(unlocked yes)
			(layer "F.SilkS")
			(effects
				(font
					(size 0.762 0.762)
					(thickness 0.2286)
				)
			)
		)
		(property "Value" "GNSS Header 16-pin"
			(at 6.740165 4.840511 0)
			(unlocked yes)
			(layer "F.SilkS")
			(hide yes)
			(effects
				(font
					(size 0.762 0.762)
					(thickness 0.2286)
				)
			)
		)
		(sheetname "05-GPS_IMU_SENSORS")
		(sheetfile "05-GPS_IMU_SENSORS.kicad_sch")
		(duplicate_pad_numbers_are_jumpers no)
		(fp_line
			(start -0.5 -7.5)
			(end 8.5 -7.5)
			(stroke
				(width 0.0254)
				(type solid)
			)
			(layer "F.SilkS")
		)
		(fp_line
			(start -0.5 0.5)
			(end -0.5 -7.5)
			(stroke
				(width 0.0254)
				(type solid)
			)
			(layer "F.SilkS")
		)
		(fp_line
			(start -0.5 0.5)
			(end 8.5 0.5)
			(stroke
				(width 0.0254)
				(type solid)
			)
			(layer "F.SilkS")
		)
		(fp_line
			(start 8.5 0.5)
			(end 8.5 -7.5)
			(stroke
				(width 0.0254)
				(type solid)
			)
			(layer "F.SilkS")
		)
		(fp_circle
			(center 0 -0.5)
			(end 0 -0.5254)
			(stroke
				(width 0.508)
				(type solid)
			)
			(fill no)
			(layer "F.SilkS")
		)
		(fp_text user "Orig 2x4"
			(at 9.610805 -0.2286 90)
			(unlocked yes)
			(layer "F.SilkS")
			(effects
				(font
					(size 0.762 0.762)
					(thickness 0.2286)
				)
				(justify left bottom)
			)
		)
		(pad "0" thru_hole circle
			(at 4 -13.49998 270)
			(size 0 0)
			(drill 0.76)
			(layers "*.Cu" "*.Mask")
			(remove_unused_layers no)
			(thermal_bridge_angle 90)
		)
		(pad "0" thru_hole circle
			(at 4 -1.5 270)
			(size 0 0)
			(drill 0.76)
			(layers "*.Cu" "*.Mask")
			(remove_unused_layers no)
			(thermal_bridge_angle 90)
		)
		(pad "1" smd rect
			(at 1.7775 -0.5 270)
			(size 1.12 2.105)
			(layers "F.Cu" "F.Mask" "F.Paste")
			(net "+5.0V")
		)
		(pad "2" smd rect
			(at 6.2225 -0.5 270)
			(size 1.12 2.105)
			(layers "F.Cu" "F.Mask" "F.Paste")
			(net "+3.3V")
		)
		(pad "3" smd rect
			(at 1.7775 -2.5 270)
			(size 1.12 2.105)
			(layers "F.Cu" "F.Mask" "F.Paste")
			(net "RCB_GPS1_TX")
		)
		(pad "4" smd rect
			(at 6.2225 -2.5 270)
			(size 1.12 2.105)
			(layers "F.Cu" "F.Mask" "F.Paste")
			(net "GPS1_RST")
		)
		(pad "5" smd rect
			(at 1.7775 -4.5 270)
			(size 1.12 2.105)
			(layers "F.Cu" "F.Mask" "F.Paste")
			(net "RCB_GPS1_RX")
		)
		(pad "6" smd rect
			(at 6.2225 -4.5 270)
			(size 1.12 2.105)
			(layers "F.Cu" "F.Mask" "F.Paste")
			(net "RCB_GPS1_TP1")
		)
		(pad "7" smd rect
			(at 1.7775 -6.5 270)
			(size 1.12 2.105)
			(layers "F.Cu" "F.Mask" "F.Paste")
			(net "RCB_GPS1_TP2")
		)
		(pad "8" smd rect
			(at 6.2225 -6.5 270)
			(size 1.12 2.105)
			(layers "F.Cu" "F.Mask" "F.Paste")
			(net "GND")
		)
		(pad "9" smd rect
			(at 1.7775 -8.50001 270)
			(size 1.12 2.105)
			(layers "F.Cu" "F.Mask" "F.Paste")
			(net "+5.0V")
		)
		(pad "10" smd rect
			(at 6.2225 -8.50001 270)
			(size 1.12 2.105)
			(layers "F.Cu" "F.Mask" "F.Paste")
			(net "+3.3V")
		)
		(pad "11" smd rect
			(at 1.7775 -10.50001 270)
			(size 1.12 2.105)
			(layers "F.Cu" "F.Mask" "F.Paste")
			(net "RCB_GPS1_PIN11")
		)
		(pad "12" smd rect
			(at 6.2225 -10.50001 270)
			(size 1.12 2.105)
			(layers "F.Cu" "F.Mask" "F.Paste")
			(net "RCB_GPS1_PIN12")
		)
		(pad "13" smd rect
			(at 1.7775 -12.5 270)
			(size 1.12 2.105)
			(layers "F.Cu" "F.Mask" "F.Paste")
			(net "GPS1_PIN13")
		)
		(pad "14" smd rect
			(at 6.2225 -12.5 270)
			(size 1.12 2.105)
			(layers "F.Cu" "F.Mask" "F.Paste")
			(net "GPS1_PIN14")
		)
		(pad "15" smd rect
			(at 1.7775 -14.5 270)
			(size 1.12 2.105)
			(layers "F.Cu" "F.Mask" "F.Paste")
			(net "GPS1_PIN15")
		)
		(pad "16" smd rect
			(at 6.2225 -14.5 270)
			(size 1.12 2.105)
			(layers "F.Cu" "F.Mask" "F.Paste")
			(net "GND")
		)
	)
	(footprint "MBRD10200CT-13:TO252(DPAK)_DIO"
		(layer "F.Cu")
		(at 215.8216 64.4162 -90)
		(property "Reference" "CR1"
			(at -3.773079 5.196795 0)
			(unlocked yes)
			(layer "F.SilkS")
			(effects
				(font
					(size 0.762 0.762)
					(thickness 0.2032)
				)
			)
		)
		(property "Value" "MBRD10200CT-13"
			(at 5.013215 8.269471 270)
			(unlocked yes)
			(layer "F.SilkS")
			(hide yes)
			(effects
				(font
					(size 0.762 0.762)
					(thickness 0.2032)
				)
			)
		)
		(sheetname "03-POWER")
		(sheetfile "03-POWER.kicad_sch")
		(duplicate_pad_numbers_are_jumpers no)
		(fp_line
			(start -0.5715 4.2418)
			(end -0.5715 3.2258)
			(stroke
				(width 0.1524)
				(type solid)
			)
			(layer "F.SilkS")
		)
		(fp_line
			(start 0.5715 4.2418)
			(end -0.5715 4.2418)
			(stroke
				(width 0.1524)
				(type solid)
			)
			(layer "F.SilkS")
		)
		(fp_line
			(start 0.5715 4.2418)
			(end 0.5715 3.2258)
			(stroke
				(width 0.1524)
				(type solid)
			)
			(layer "F.SilkS")
		)
		(fp_line
			(start -3.4798 3.2258)
			(end -3.4798 -3.2258)
			(stroke
				(width 0.1524)
				(type solid)
			)
			(layer "F.SilkS")
		)
		(fp_line
			(start -0.5715 3.2258)
			(end -3.4798 3.2258)
			(stroke
				(width 0.1524)
				(type solid)
			)
			(layer "F.SilkS")
		)
		(fp_line
			(start 3.4798 3.2258)
			(end 0.5715 3.2258)
			(stroke
				(width 0.1524)
				(type solid)
			)
			(layer "F.SilkS")
		)
		(fp_line
			(start 3.4798 3.2258)
			(end 3.4798 -3.2258)
			(stroke
				(width 0.1524)
				(type solid)
			)
			(layer "F.SilkS")
		)
		(fp_line
			(start -3.08864 -3.2258)
			(end -3.4798 -3.2258)
			(stroke
				(width 0.1524)
				(type solid)
			)
			(layer "F.SilkS")
		)
		(fp_line
			(start 3.4798 -3.2258)
			(end 3.08864 -3.2258)
			(stroke
				(width 0.1524)
				(type solid)
			)
			(layer "F.SilkS")
		)
		(fp_text user "*"
			(at -5.5245 5.946775 270)
			(unlocked yes)
			(layer "F.SilkS")
			(effects
				(font
					(size 1.27 1.27)
					(thickness 0.0762)
				)
				(justify left bottom)
			)
		)
		(pad "1" smd rect
			(at -2.286 5.1562 270)
			(size 0.9398 2.4892)
			(layers "F.Cu" "F.Mask" "F.Paste")
			(net "NetCR1_1")
			(solder_mask_margin 0)
			(solder_paste_margin 0)
		)
		(pad "2" smd rect
			(at 0 -1.7653 270)
			(size 5.5118 5.9182)
			(layers "F.Cu" "F.Mask" "F.Paste")
			(net "NetCR1_2")
			(solder_mask_margin 0)
			(solder_paste_margin 0)
		)
		(pad "3" smd rect
			(at 2.286 5.1562 270)
			(size 0.9398 2.4892)
			(layers "F.Cu" "F.Mask" "F.Paste")
			(net "+12V_PCIE")
			(solder_mask_margin 0)
			(solder_paste_margin 0)
		)
	)
	(footprint "Vault:M08A_L"
		(layer "F.Cu")
		(at 124.6216 86.1162 90)
		(property "Reference" "U4"
			(at 1.028595 -3.235469 90)
			(unlocked yes)
			(layer "F.SilkS")
			(effects
				(font
					(size 0.762 0.762)
					(thickness 0.2286)
				)
			)
		)
		(property "Value" "DS90LV028AQMA"
			(at 6.71518 4.180071 90)
			(unlocked yes)
			(layer "F.SilkS")
			(hide yes)
			(effects
				(font
					(size 0.762 0.762)
					(thickness 0.2286)
				)
			)
		)
		(sheetname "06-MAC")
		(sheetfile "06-MAC.kicad_sch")
		(duplicate_pad_numbers_are_jumpers no)
		(fp_line
			(start 1 -2.5)
			(end 1 2.5)
			(stroke
				(width 0.2)
				(type solid)
			)
			(layer "F.SilkS")
		)
		(fp_line
			(start -1 -2.5)
			(end 1 -2.5)
			(stroke
				(width 0.2)
				(type solid)
			)
			(layer "F.SilkS")
		)
		(fp_line
			(start -1 -2.5)
			(end -1 2.5)
			(stroke
				(width 0.2)
				(type solid)
			)
			(layer "F.SilkS")
		)
		(fp_line
			(start -1 2.5)
			(end 1 2.5)
			(stroke
				(width 0.2)
				(type solid)
			)
			(layer "F.SilkS")
		)
		(fp_circle
			(center -2.35 -2.755)
			(end -2.225 -2.755)
			(stroke
				(width 0.25)
				(type solid)
			)
			(fill no)
			(layer "F.SilkS")
		)
		(fp_circle
			(center -0.2 -1.7)
			(end 0 -1.7)
			(stroke
				(width 0.4)
				(type solid)
			)
			(fill no)
			(layer "F.SilkS")
		)
		(pad "1" smd oval
			(at -2.35 -1.905 180)
			(size 0.6 1.9)
			(layers "F.Cu" "F.Mask" "F.Paste")
			(net "MAC_PPS_OUT-")
		)
		(pad "2" smd oval
			(at -2.35 -0.635 180)
			(size 0.6 1.9)
			(layers "F.Cu" "F.Mask" "F.Paste")
			(net "MAC_PPS_OUT+")
		)
		(pad "3" smd oval
			(at -2.35 0.635 180)
			(size 0.6 1.9)
			(layers "F.Cu" "F.Mask" "F.Paste")
		)
		(pad "4" smd oval
			(at -2.35 1.905 180)
			(size 0.6 1.9)
			(layers "F.Cu" "F.Mask" "F.Paste")
		)
		(pad "5" smd oval
			(at 2.35 1.905 180)
			(size 0.6 1.9)
			(layers "F.Cu" "F.Mask" "F.Paste")
			(net "GND")
		)
		(pad "6" smd oval
			(at 2.35 0.635 180)
			(size 0.6 1.9)
			(layers "F.Cu" "F.Mask" "F.Paste")
		)
		(pad "7" smd oval
			(at 2.35 -0.635 180)
			(size 0.6 1.9)
			(layers "F.Cu" "F.Mask" "F.Paste")
			(net "FPGA_MAC_PPSDIFF_OUT")
		)
		(pad "8" smd oval
			(at 2.35 -1.905 180)
			(size 0.6 1.9)
			(layers "F.Cu" "F.Mask" "F.Paste")
			(net "+3.3V")
		)
	)
	(footprint "Vault:FP-ERJ2R-MFG"
		(layer "F.Cu")
		(at 227.2216 120.3162)
		(property "Reference" "R83"
			(at -2.1714 0.426931 0)
			(unlocked yes)
			(layer "F.SilkS")
			(effects
				(font
					(size 0.762 0.762)
					(thickness 0.2286)
				)
			)
		)
		(property "Value" "15K_1%_0402"
			(at -2.732271 8.011115 270)
			(unlocked yes)
			(layer "F.SilkS")
			(hide yes)
			(effects
				(font
					(size 0.762 0.762)
					(thickness 0.2286)
				)
			)
		)
		(sheetname "09-USBUart_PPSMUX_UARTMUX")
		(sheetfile "09-USBUart_PPSMUX_UARTMUX.kicad_sch")
		(duplicate_pad_numbers_are_jumpers no)
		(fp_line
			(start -0.529 0.636)
			(end 0.521 0.636)
			(stroke
				(width 0.2)
				(type solid)
			)
			(layer "F.SilkS")
		)
		(fp_line
			(start -0.525 -0.65)
			(end 0.525 -0.65)
			(stroke
				(width 0.2)
				(type solid)
			)
			(layer "F.SilkS")
		)
		(fp_line
			(start -0.85 -0.375)
			(end 0.85 -0.375)
			(stroke
				(width 0.2)
				(type solid)
			)
			(layer "F.CrtYd")
		)
		(fp_line
			(start -0.85 0.375)
			(end -0.85 -0.375)
			(stroke
				(width 0.2)
				(type solid)
			)
			(layer "F.CrtYd")
		)
		(fp_line
			(start -0.85 0.375)
			(end 0.85 0.375)
			(stroke
				(width 0.2)
				(type solid)
			)
			(layer "F.CrtYd")
		)
		(fp_line
			(start 0.85 0.375)
			(end 0.85 -0.375)
			(stroke
				(width 0.2)
				(type solid)
			)
			(layer "F.CrtYd")
		)
		(fp_line
			(start -0.85 -0.375)
			(end 0.85 -0.375)
			(stroke
				(width 0.2)
				(type solid)
			)
			(layer "F.Fab")
		)
		(fp_line
			(start -0.85 0.375)
			(end -0.85 -0.375)
			(stroke
				(width 0.2)
				(type solid)
			)
			(layer "F.Fab")
		)
		(fp_line
			(start -0.85 0.375)
			(end 0.85 0.375)
			(stroke
				(width 0.2)
				(type solid)
			)
			(layer "F.Fab")
		)
		(fp_line
			(start -0.5 0)
			(end 0.5 0)
			(stroke
				(width 0.1)
				(type solid)
			)
			(layer "F.Fab")
		)
		(fp_line
			(start 0 0.5)
			(end 0 -0.5)
			(stroke
				(width 0.1)
				(type solid)
			)
			(layer "F.Fab")
		)
		(fp_line
			(start 0.85 0.375)
			(end 0.85 -0.375)
			(stroke
				(width 0.2)
				(type solid)
			)
			(layer "F.Fab")
		)
		(fp_text user "${REFERENCE}"
			(at -0.00001 0.09602 360)
			(unlocked yes)
			(layer "F.Fab")
			(effects
				(font
					(face "Arial")
					(size 0.63 0.63)
					(thickness 0.1)
				)
				(justify left bottom)
			)
		)
		(pad "1" smd rect
			(at -0.5125 0)
			(size 0.475 0.5)
			(layers "F.Cu" "F.Mask" "F.Paste")
			(net "GND")
			(solder_mask_margin 0)
			(solder_paste_margin 0)
		)
		(pad "2" smd rect
			(at 0.5125 0)
			(size 0.475 0.5)
			(layers "F.Cu" "F.Mask" "F.Paste")
			(net "NetC91_1")
			(solder_mask_margin 0)
			(solder_paste_margin 0)
		)
	)
	(footprint "Vault:RESC1005X40X25NL05T05"
		(layer "F.Cu")
		(at 227.6216 113.2162 180)
		(property "Reference" "R42"
			(at -0.3286 0.773079 0)
			(unlocked yes)
			(layer "F.SilkS")
			(effects
				(font
					(size 0.762 0.762)
					(thickness 0.2286)
				)
			)
		)
		(property "Value" "27_1%_0402"
			(at -3.011631 6.10665 90)
			(unlocked yes)
			(layer "F.SilkS")
			(hide yes)
			(effects
				(font
					(size 0.762 0.762)
					(thickness 0.2286)
				)
			)
		)
		(sheetname "09-USBUart_PPSMUX_UARTMUX")
		(sheetfile "09-USBUart_PPSMUX_UARTMUX.kicad_sch")
		(duplicate_pad_numbers_are_jumpers no)
		(pad "1" smd rect
			(at -0.45 0 270)
			(size 0.55 0.55)
			(layers "F.Cu" "F.Mask" "F.Paste")
			(net "NetR42_1")
		)
		(pad "2" smd rect
			(at 0.45 0 270)
			(size 0.55 0.55)
			(layers "F.Cu" "F.Mask" "F.Paste")
			(net "FTDI_RX")
		)
	)
	(footprint "SA53:SolderSocket"
		(locked yes)
		(layer "F.Cu")
		(at 127.5216 137.3162 90)
		(property "Reference" "SKT9"
			(at -0.126931 7.1286 0)
			(unlocked yes)
			(layer "F.SilkS")
			(effects
				(font
					(size 0.762 0.762)
					(thickness 0.2286)
				)
			)
		)
		(property "Value" "0332-0-43-80-18-27-10-0"
			(at -2.910071 16.1362 0)
			(unlocked yes)
			(layer "F.SilkS")
			(hide yes)
			(effects
				(font
					(size 0.762 0.762)
					(thickness 0.2286)
				)
			)
		)
		(sheetname "06-MAC")
		(sheetfile "06-MAC.kicad_sch")
		(duplicate_pad_numbers_are_jumpers no)
		(pad "1" thru_hole circle
			(at 0 0 90)
			(size 2.54 2.54)
			(drill 2.0066)
			(layers "*.Cu" "*.Mask")
			(remove_unused_layers no)
			(net "GND")
			(thermal_bridge_angle 90)
		)
	)
	(footprint "Vault:FP-0402-L_1_0_0_05-W_0_5-IPC_A"
		(layer "B.Cu")
		(at 223.56155 127.69916 -90)
		(property "Reference" "C114"
			(at -0.13696 -1.533119 270)
			(unlocked yes)
			(layer "B.SilkS")
			(effects
				(font
					(size 0.762 0.762)
					(thickness 0.254)
				)
				(justify mirror)
			)
		)
		(property "Value" "1uF_16V_0402"
			(at -2.744961 -8.315705 180)
			(unlocked yes)
			(layer "B.SilkS")
			(hide yes)
			(effects
				(font
					(size 0.762 0.762)
					(thickness 0.254)
				)
				(justify mirror)
			)
		)
		(sheetname "09-USBUart_PPSMUX_UARTMUX")
		(sheetfile "09-USBUart_PPSMUX_UARTMUX.kicad_sch")
		(duplicate_pad_numbers_are_jumpers no)
		(fp_line
			(start 0.83623 0.73624)
			(end -0.83624 0.73624)
			(stroke
				(width 0.2)
				(type solid)
			)
			(layer "B.SilkS")
		)
		(fp_line
			(start 0.83623 -0.73623)
			(end -0.83624 -0.73623)
			(stroke
				(width 0.2)
				(type solid)
			)
			(layer "B.SilkS")
		)
		(fp_line
			(start -1.03624 0.53624)
			(end -1.03624 -0.53623)
			(stroke
				(width 0.2)
				(type solid)
			)
			(layer "B.CrtYd")
		)
		(fp_line
			(start 1.03623 0.53624)
			(end -1.03624 0.53624)
			(stroke
				(width 0.2)
				(type solid)
			)
			(layer "B.CrtYd")
		)
		(fp_line
			(start 1.03623 0.53624)
			(end 1.03623 -0.53623)
			(stroke
				(width 0.2)
				(type solid)
			)
			(layer "B.CrtYd")
		)
		(fp_line
			(start 1.03623 -0.53623)
			(end -1.03624 -0.53623)
			(stroke
				(width 0.2)
				(type solid)
			)
			(layer "B.CrtYd")
		)
		(fp_line
			(start -1.03624 0.53624)
			(end -1.03624 -0.53623)
			(stroke
				(width 0.2)
				(type solid)
			)
			(layer "B.Fab")
		)
		(fp_line
			(start 1.03623 0.53624)
			(end -1.03624 0.53624)
			(stroke
				(width 0.2)
				(type solid)
			)
			(layer "B.Fab")
		)
		(fp_line
			(start 1.03623 0.53624)
			(end 1.03623 -0.53623)
			(stroke
				(width 0.2)
				(type solid)
			)
			(layer "B.Fab")
		)
		(fp_line
			(start 0 0.5)
			(end 0 -0.5)
			(stroke
				(width 0.1)
				(type solid)
			)
			(layer "B.Fab")
		)
		(fp_line
			(start 0.49999 0)
			(end -0.5 0)
			(stroke
				(width 0.1)
				(type solid)
			)
			(layer "B.Fab")
		)
		(fp_line
			(start 1.03623 -0.53623)
			(end -1.03624 -0.53623)
			(stroke
				(width 0.2)
				(type solid)
			)
			(layer "B.Fab")
		)
		(fp_text user "${REFERENCE}"
			(at -0.00001 -0.09601 90)
			(unlocked yes)
			(layer "B.Fab")
			(effects
				(font
					(face "Arial")
					(size 0.63 0.63)
					(thickness 0.1)
				)
				(justify left bottom mirror)
			)
		)
		(pad "1" smd rect
			(at -0.47857 0 270)
			(size 0.71535 0.67248)
			(layers "B.Cu" "B.Mask" "B.Paste")
			(net "FTDI_VBUS")
			(solder_mask_margin 0)
			(solder_paste_margin 0)
		)
		(pad "2" smd rect
			(at 0.47856 0 270)
			(size 0.71535 0.67248)
			(layers "B.Cu" "B.Mask" "B.Paste")
			(net "GND")
			(solder_mask_margin 0)
			(solder_paste_margin 0)
		)
	)
	(footprint "Vault:RESC1005X40X25ML05T05"
		(layer "B.Cu")
		(at 213.53831 125.11792)
		(property "Reference" "R182"
			(at -0.59568 -1.574789 0)
			(unlocked yes)
			(layer "B.SilkS")
			(effects
				(font
					(size 0.762 0.762)
					(thickness 0.254)
				)
				(justify mirror)
			)
		)
		(property "Value" "10K_5%_0402"
			(at -2.884671 -8.061875 270)
			(unlocked yes)
			(layer "B.SilkS")
			(hide yes)
			(effects
				(font
					(size 0.762 0.762)
					(thickness 0.254)
				)
				(justify mirror)
			)
		)
		(sheetname "09-USBUart_PPSMUX_UARTMUX")
		(sheetfile "09-USBUart_PPSMUX_UARTMUX.kicad_sch")
		(duplicate_pad_numbers_are_jumpers no)
		(pad "1" smd rect
			(at -0.5 0 270)
			(size 0.65 0.65)
			(layers "B.Cu" "B.Mask" "B.Paste")
			(net "GND")
		)
		(pad "2" smd rect
			(at 0.5 0 270)
			(size 0.65 0.65)
			(layers "B.Cu" "B.Mask" "B.Paste")
			(net "NetR180_1")
		)
	)
	(footprint "Vault:RESC1005X40X25NL10T10"
		(layer "B.Cu")
		(at 126.8216 64.41711 90)
		(property "Reference" "R133"
			(at 2.29771 0.026921 90)
			(unlocked yes)
			(layer "B.SilkS")
			(effects
				(font
					(size 0.762 0.762)
					(thickness 0.2032)
				)
				(justify mirror)
			)
		)
		(property "Value" "4.7K_1%_0402"
			(at -2.732271 -8.747465 0)
			(unlocked yes)
			(layer "B.SilkS")
			(hide yes)
			(effects
				(font
					(size 0.762 0.762)
					(thickness 0.2032)
				)
				(justify mirror)
			)
		)
		(sheetname "10-M2_GPS")
		(sheetfile "10-M2_GPS.kicad_sch")
		(duplicate_pad_numbers_are_jumpers no)
		(pad "1" smd rect
			(at -0.425 0)
			(size 0.6 0.65)
			(layers "B.Cu" "B.Mask" "B.Paste")
			(net "GPS1_PIN14")
		)
		(pad "2" smd rect
			(at 0.425 0)
			(size 0.6 0.65)
			(layers "B.Cu" "B.Mask" "B.Paste")
			(net "+3.3V")
		)
	)
)
